# S9S_MB_2U (Grand Teton) — schematic netlist excerpt (pin names and nets, part order shuffled) for the footprints in the layout excerpt that follows; sources: Cadence DE-HDL packaged netlist, KiCad conversion of 03242023_DA0F0TMBIJ0_F0T_Motherboard_J_brd_V01_OCP.brd

R4112  Q_RES  10K 1% CHIP  pkg 0402LF  page 184 : A = PD_PCH_GPP_E_12 ; B = GND
R3959  Q_RES  0 5% CHIP  pkg 0402LF  page 192 : A = P3V3_E1S_UV_0_R ; B = P3V3_E1S_UV_0

(kicad_pcb
	(version 20260206)
	(generator "pcbnew")
	(generator_version "10.0")
	(general
		(thickness 1.6)
		(legacy_teardrops no)
	)
	(paper "A4")
	(title_block
		(title "03242023_DA0F0TMBIJ0_F0T_Motherboard_J_brd_V01_OCP.brd")
		(comment 1 "Grand Teton / footprints 5528-5529 of 6105")
	)
	(layers
		(0 "F.Cu" signal "TOP")
		(4 "In1.Cu" signal "GND")
		(6 "In2.Cu" signal "IN1")
		(8 "In3.Cu" signal "GND1")
		(10 "In4.Cu" signal "IN2")
		(12 "In5.Cu" signal "GND2")
		(14 "In6.Cu" signal "IN3")
		(16 "In7.Cu" signal "GND3")
		(18 "In8.Cu" signal "VCC")
		(20 "In9.Cu" signal "VCC1")
		(22 "In10.Cu" signal "GND4")
		(24 "In11.Cu" signal "IN4")
		(26 "In12.Cu" signal "GND5")
		(28 "In13.Cu" signal "IN5")
		(30 "In14.Cu" signal "GND6")
		(32 "In15.Cu" signal "IN6")
		(34 "In16.Cu" signal "GND7")
		(2 "B.Cu" signal "BOTTOM")
		(9 "F.Adhes" user "F.Adhesive")
		(11 "B.Adhes" user "B.Adhesive")
		(13 "F.Paste" user "Package Geometry/Pastemask Top")
		(15 "B.Paste" user "Package Geometry/Pastemask Bottom")
		(5 "F.SilkS" user "Ref Des/Silkscreen Top")
		(7 "B.SilkS" user "Ref Des/Silkscreen Bottom")
		(1 "F.Mask" user "Board Geometry/Soldermask Top")
		(3 "B.Mask" user "Board Geometry/Soldermask Bottom")
		(17 "Dwgs.User" user "User.Drawings")
		(19 "Cmts.User" user "User.Comments")
		(21 "Eco1.User" user "User.Eco1")
		(23 "Eco2.User" user "User.Eco2")
		(25 "Edge.Cuts" user "Board Geometry/Outline")
		(27 "Margin" user)
		(31 "F.CrtYd" user "Package Geometry/Place Bound Top")
		(29 "B.CrtYd" user "Package Geometry/Place Bound Bottom")
		(35 "F.Fab" user "Ref Des/Assembly Top")
		(33 "B.Fab" user "Ref Des/Assembly Bottom")
	)
	(footprint ""
		(layer "B.Cu")
		(at 369.49888 -38.953948 180)
		(property "Reference" "R4112"
			(at 0 0 0)
			(layer "B.SilkS")
			(hide yes)
			(effects
				(font
					(size 1.27 1.27)
				)
				(justify mirror)
			)
		)
		(property "Value" ""
			(at 0 0 0)
			(layer "B.Fab")
			(effects
				(font
					(size 1.27 1.27)
				)
				(justify mirror)
			)
		)
		(duplicate_pad_numbers_are_jumpers no)
		(fp_line
			(start 0.7874 0.4064)
			(end 0.7874 -0.4064)
			(stroke
				(width 0.1524)
				(type default)
			)
			(layer "B.SilkS")
		)
		(fp_line
			(start 0.7874 -0.4064)
			(end -0.7874 -0.4064)
			(stroke
				(width 0.1524)
				(type default)
			)
			(layer "B.SilkS")
		)
		(fp_line
			(start -0.7874 0.4064)
			(end 0.7874 0.4064)
			(stroke
				(width 0.1524)
				(type default)
			)
			(layer "B.SilkS")
		)
		(fp_line
			(start -0.7874 -0.4064)
			(end -0.7874 0.4064)
			(stroke
				(width 0.1524)
				(type default)
			)
			(layer "B.SilkS")
		)
		(fp_line
			(start 0.67945 0.3048)
			(end 0.67945 -0.305054)
			(stroke
				(width 0.1)
				(type default)
			)
			(layer "B.Fab")
		)
		(fp_line
			(start 0.67945 -0.305054)
			(end 0.12065 -0.305054)
			(stroke
				(width 0.1)
				(type default)
			)
			(layer "B.Fab")
		)
		(fp_line
			(start 0.12065 0.3048)
			(end 0.67945 0.3048)
			(stroke
				(width 0.1)
				(type default)
			)
			(layer "B.Fab")
		)
		(fp_line
			(start 0.12065 0.2794)
			(end 0.12065 0.3048)
			(stroke
				(width 0.1)
				(type default)
			)
			(layer "B.Fab")
		)
		(fp_line
			(start 0.12065 -0.2794)
			(end -0.12065 -0.2794)
			(stroke
				(width 0.1)
				(type default)
			)
			(layer "B.Fab")
		)
		(fp_line
			(start 0.12065 -0.305054)
			(end 0.12065 -0.2794)
			(stroke
				(width 0.1)
				(type default)
			)
			(layer "B.Fab")
		)
		(fp_line
			(start -0.120396 0.3048)
			(end -0.120396 0.2794)
			(stroke
				(width 0.1)
				(type default)
			)
			(layer "B.Fab")
		)
		(fp_line
			(start -0.120396 0.2794)
			(end 0.12065 0.2794)
			(stroke
				(width 0.1)
				(type default)
			)
			(layer "B.Fab")
		)
		(fp_line
			(start -0.12065 -0.2794)
			(end -0.12065 -0.3048)
			(stroke
				(width 0.1)
				(type default)
			)
			(layer "B.Fab")
		)
		(fp_line
			(start -0.12065 -0.3048)
			(end -0.67945 -0.3048)
			(stroke
				(width 0.1)
				(type default)
			)
			(layer "B.Fab")
		)
		(fp_line
			(start -0.67945 0.3048)
			(end -0.120396 0.3048)
			(stroke
				(width 0.1)
				(type default)
			)
			(layer "B.Fab")
		)
		(fp_line
			(start -0.67945 -0.3048)
			(end -0.67945 0.3048)
			(stroke
				(width 0.1)
				(type default)
			)
			(layer "B.Fab")
		)
		(pad "1" smd circle
			(at 0.40005 0)
			(size 0 0)
			(layers "B.Cu" "B.Mask" "B.Paste")
			(net "PD_PCH_GPP_E_12")
		)
		(pad "2" smd circle
			(at -0.40005 0)
			(size 0 0)
			(layers "B.Cu" "B.Mask" "B.Paste")
			(net "GND")
		)
	)
	(footprint ""
		(layer "B.Cu")
		(at 218.83751 -68.38188 180)
		(property "Reference" "R3959"
			(at 0 0 0)
			(layer "B.SilkS")
			(hide yes)
			(effects
				(font
					(size 1.27 1.27)
				)
				(justify mirror)
			)
		)
		(property "Value" ""
			(at 0 0 0)
			(layer "B.Fab")
			(effects
				(font
					(size 1.27 1.27)
				)
				(justify mirror)
			)
		)
		(duplicate_pad_numbers_are_jumpers no)
		(fp_line
			(start 0.7874 0.4064)
			(end 0.7874 -0.4064)
			(stroke
				(width 0.1524)
				(type default)
			)
			(layer "B.SilkS")
		)
		(fp_line
			(start 0.7874 -0.4064)
			(end -0.7874 -0.4064)
			(stroke
				(width 0.1524)
				(type default)
			)
			(layer "B.SilkS")
		)
		(fp_line
			(start -0.7874 0.4064)
			(end 0.7874 0.4064)
			(stroke
				(width 0.1524)
				(type default)
			)
			(layer "B.SilkS")
		)
		(fp_line
			(start -0.7874 -0.4064)
			(end -0.7874 0.4064)
			(stroke
				(width 0.1524)
				(type default)
			)
			(layer "B.SilkS")
		)
		(fp_line
			(start 0.67945 0.3048)
			(end 0.67945 -0.305054)
			(stroke
				(width 0.1)
				(type default)
			)
			(layer "B.Fab")
		)
		(fp_line
			(start 0.67945 -0.305054)
			(end 0.12065 -0.305054)
			(stroke
				(width 0.1)
				(type default)
			)
			(layer "B.Fab")
		)
		(fp_line
			(start 0.12065 0.3048)
			(end 0.67945 0.3048)
			(stroke
				(width 0.1)
				(type default)
			)
			(layer "B.Fab")
		)
		(fp_line
			(start 0.12065 0.2794)
			(end 0.12065 0.3048)
			(stroke
				(width 0.1)
				(type default)
			)
			(layer "B.Fab")
		)
		(fp_line
			(start 0.12065 -0.2794)
			(end -0.12065 -0.2794)
			(stroke
				(width 0.1)
				(type default)
			)
			(layer "B.Fab")
		)
		(fp_line
			(start 0.12065 -0.305054)
			(end 0.12065 -0.2794)
			(stroke
				(width 0.1)
				(type default)
			)
			(layer "B.Fab")
		)
		(fp_line
			(start -0.120396 0.3048)
			(end -0.120396 0.2794)
			(stroke
				(width 0.1)
				(type default)
			)
			(layer "B.Fab")
		)
		(fp_line
			(start -0.120396 0.2794)
			(end 0.12065 0.2794)
			(stroke
				(width 0.1)
				(type default)
			)
			(layer "B.Fab")
		)
		(fp_line
			(start -0.12065 -0.2794)
			(end -0.12065 -0.3048)
			(stroke
				(width 0.1)
				(type default)
			)
			(layer "B.Fab")
		)
		(fp_line
			(start -0.12065 -0.3048)
			(end -0.67945 -0.3048)
			(stroke
				(width 0.1)
				(type default)
			)
			(layer "B.Fab")
		)
		(fp_line
			(start -0.67945 0.3048)
			(end -0.120396 0.3048)
			(stroke
				(width 0.1)
				(type default)
			)
			(layer "B.Fab")
		)
		(fp_line
			(start -0.67945 -0.3048)
			(end -0.67945 0.3048)
			(stroke
				(width 0.1)
				(type default)
			)
			(layer "B.Fab")
		)
		(pad "1" smd circle
			(at 0.40005 0)
			(size 0 0)
			(layers "B.Cu" "B.Mask" "B.Paste")
			(net "P3V3_E1S_UV_0_R")
		)
		(pad "2" smd circle
			(at -0.40005 0)
			(size 0 0)
			(layers "B.Cu" "B.Mask" "B.Paste")
			(net "P3V3_E1S_UV_0")
		)
	)
)
